# T6G (Grand Teton) — schematic netlist excerpt (pin names and nets, part order shuffled) for the footprints in the layout excerpt that follows; sources: Cadence DE-HDL packaged netlist, KiCad conversion of 04192023_DAF0TMB3IC0_F0TG_MB_C_brd_V02_OCP.brd

R3317  Q_RES  4.7K 5% EMPTY  pkg 0402LF  page 130 : A = P3V3_AUX ; B = GPU_FPGA_RST_R1_BUF_N
R352  Q_RES  33 5% CHIP  pkg 0402LF  page 151 : A = SMB_SCM_2_R5_SDA ; B = SMB_SCM_2_R6_SDA

(kicad_pcb
	(version 20260206)
	(generator "pcbnew")
	(generator_version "10.0")
	(general
		(thickness 1.6)
		(legacy_teardrops no)
	)
	(paper "A4")
	(title_block
		(title "04192023_DAF0TMB3IC0_F0TG_MB_C_brd_V02_OCP.brd")
		(comment 1 "Grand Teton / footprints 1568-1569 of 8354")
	)
	(layers
		(0 "F.Cu" signal "TOP")
		(4 "In1.Cu" signal "GND")
		(6 "In2.Cu" signal "IN1")
		(8 "In3.Cu" signal "GND1")
		(10 "In4.Cu" signal "IN2")
		(12 "In5.Cu" signal "GND2")
		(14 "In6.Cu" signal "IN3")
		(16 "In7.Cu" signal "GND3")
		(18 "In8.Cu" signal "VCC")
		(20 "In9.Cu" signal "VCC1")
		(22 "In10.Cu" signal "GND4")
		(24 "In11.Cu" signal "IN4")
		(26 "In12.Cu" signal "GND5")
		(28 "In13.Cu" signal "IN5")
		(30 "In14.Cu" signal "GND6")
		(32 "In15.Cu" signal "IN6")
		(34 "In16.Cu" signal "GND7")
		(2 "B.Cu" signal "BOTTOM")
		(9 "F.Adhes" user "F.Adhesive")
		(11 "B.Adhes" user "B.Adhesive")
		(13 "F.Paste" user "Package Geometry/Pastemask Top")
		(15 "B.Paste" user "Package Geometry/Pastemask Bottom")
		(5 "F.SilkS" user "Ref Des/Silkscreen Top")
		(7 "B.SilkS" user "Ref Des/Silkscreen Bottom")
		(1 "F.Mask" user "Board Geometry/Soldermask Top")
		(3 "B.Mask" user "Board Geometry/Soldermask Bottom")
		(17 "Dwgs.User" user "User.Drawings")
		(19 "Cmts.User" user "User.Comments")
		(21 "Eco1.User" user "User.Eco1")
		(23 "Eco2.User" user "User.Eco2")
		(25 "Edge.Cuts" user "Board Geometry/Outline")
		(27 "Margin" user)
		(31 "F.CrtYd" user "Package Geometry/Place Bound Top")
		(29 "B.CrtYd" user "Package Geometry/Place Bound Bottom")
		(35 "F.Fab" user "Ref Des/Assembly Top")
		(33 "B.Fab" user "Ref Des/Assembly Bottom")
	)
	(footprint ""
		(layer "F.Cu")
		(at 47.18304 -434.057552 90)
		(property "Reference" "R3317"
			(at 0 0 90)
			(layer "F.SilkS")
			(hide yes)
			(effects
				(font
					(size 1.27 1.27)
				)
			)
		)
		(property "Value" ""
			(at 0 0 90)
			(layer "F.Fab")
			(effects
				(font
					(size 1.27 1.27)
				)
			)
		)
		(duplicate_pad_numbers_are_jumpers no)
		(fp_line
			(start 0.7874 -0.4064)
			(end 0.7874 0.4064)
			(stroke
				(width 0.1524)
				(type default)
			)
			(layer "F.SilkS")
		)
		(fp_line
			(start -0.7874 -0.4064)
			(end 0.7874 -0.4064)
			(stroke
				(width 0.1524)
				(type default)
			)
			(layer "F.SilkS")
		)
		(fp_line
			(start 0.7874 0.4064)
			(end -0.7874 0.4064)
			(stroke
				(width 0.1524)
				(type default)
			)
			(layer "F.SilkS")
		)
		(fp_line
			(start -0.7874 0.4064)
			(end -0.7874 -0.4064)
			(stroke
				(width 0.1524)
				(type default)
			)
			(layer "F.SilkS")
		)
		(fp_line
			(start -0.12065 -0.305054)
			(end -0.12065 -0.2794)
			(stroke
				(width 0.1)
				(type default)
			)
			(layer "F.Fab")
		)
		(fp_line
			(start -0.67945 -0.305054)
			(end -0.12065 -0.305054)
			(stroke
				(width 0.1)
				(type default)
			)
			(layer "F.Fab")
		)
		(fp_line
			(start 0.67945 -0.3048)
			(end 0.67945 0.3048)
			(stroke
				(width 0.1)
				(type default)
			)
			(layer "F.Fab")
		)
		(fp_line
			(start 0.12065 -0.3048)
			(end 0.67945 -0.3048)
			(stroke
				(width 0.1)
				(type default)
			)
			(layer "F.Fab")
		)
		(fp_line
			(start 0.12065 -0.2794)
			(end 0.12065 -0.3048)
			(stroke
				(width 0.1)
				(type default)
			)
			(layer "F.Fab")
		)
		(fp_line
			(start -0.12065 -0.2794)
			(end 0.12065 -0.2794)
			(stroke
				(width 0.1)
				(type default)
			)
			(layer "F.Fab")
		)
		(fp_line
			(start 0.120396 0.2794)
			(end -0.12065 0.2794)
			(stroke
				(width 0.1)
				(type default)
			)
			(layer "F.Fab")
		)
		(fp_line
			(start -0.12065 0.2794)
			(end -0.12065 0.3048)
			(stroke
				(width 0.1)
				(type default)
			)
			(layer "F.Fab")
		)
		(fp_line
			(start 0.67945 0.3048)
			(end 0.120396 0.3048)
			(stroke
				(width 0.1)
				(type default)
			)
			(layer "F.Fab")
		)
		(fp_line
			(start 0.120396 0.3048)
			(end 0.120396 0.2794)
			(stroke
				(width 0.1)
				(type default)
			)
			(layer "F.Fab")
		)
		(fp_line
			(start -0.12065 0.3048)
			(end -0.67945 0.3048)
			(stroke
				(width 0.1)
				(type default)
			)
			(layer "F.Fab")
		)
		(fp_line
			(start -0.67945 0.3048)
			(end -0.67945 -0.305054)
			(stroke
				(width 0.1)
				(type default)
			)
			(layer "F.Fab")
		)
		(pad "1" smd circle
			(at -0.40005 0 90)
			(size 0 0)
			(layers "F.Cu" "F.Mask" "F.Paste")
			(net "P3V3_AUX")
		)
		(pad "2" smd circle
			(at 0.40005 0 90)
			(size 0 0)
			(layers "F.Cu" "F.Mask" "F.Paste")
			(net "GPU_FPGA_RST_R1_BUF_N")
		)
	)
	(footprint ""
		(layer "F.Cu")
		(at 325.9074 -363.22)
		(property "Reference" "R352"
			(at 0 0 0)
			(layer "F.SilkS")
			(hide yes)
			(effects
				(font
					(size 1.27 1.27)
				)
			)
		)
		(property "Value" ""
			(at 0 0 0)
			(layer "F.Fab")
			(effects
				(font
					(size 1.27 1.27)
				)
			)
		)
		(duplicate_pad_numbers_are_jumpers no)
		(fp_line
			(start -0.7874 -0.4064)
			(end 0.7874 -0.4064)
			(stroke
				(width 0.1524)
				(type default)
			)
			(layer "F.SilkS")
		)
		(fp_line
			(start -0.7874 0.4064)
			(end -0.7874 -0.4064)
			(stroke
				(width 0.1524)
				(type default)
			)
			(layer "F.SilkS")
		)
		(fp_line
			(start 0.7874 -0.4064)
			(end 0.7874 0.4064)
			(stroke
				(width 0.1524)
				(type default)
			)
			(layer "F.SilkS")
		)
		(fp_line
			(start 0.7874 0.4064)
			(end -0.7874 0.4064)
			(stroke
				(width 0.1524)
				(type default)
			)
			(layer "F.SilkS")
		)
		(fp_line
			(start -0.67945 -0.305054)
			(end -0.12065 -0.305054)
			(stroke
				(width 0.1)
				(type default)
			)
			(layer "F.Fab")
		)
		(fp_line
			(start -0.67945 0.3048)
			(end -0.67945 -0.305054)
			(stroke
				(width 0.1)
				(type default)
			)
			(layer "F.Fab")
		)
		(fp_line
			(start -0.12065 -0.305054)
			(end -0.12065 -0.2794)
			(stroke
				(width 0.1)
				(type default)
			)
			(layer "F.Fab")
		)
		(fp_line
			(start -0.12065 -0.2794)
			(end 0.12065 -0.2794)
			(stroke
				(width 0.1)
				(type default)
			)
			(layer "F.Fab")
		)
		(fp_line
			(start -0.12065 0.2794)
			(end -0.12065 0.3048)
			(stroke
				(width 0.1)
				(type default)
			)
			(layer "F.Fab")
		)
		(fp_line
			(start -0.12065 0.3048)
			(end -0.67945 0.3048)
			(stroke
				(width 0.1)
				(type default)
			)
			(layer "F.Fab")
		)
		(fp_line
			(start 0.120396 0.2794)
			(end -0.12065 0.2794)
			(stroke
				(width 0.1)
				(type default)
			)
			(layer "F.Fab")
		)
		(fp_line
			(start 0.120396 0.3048)
			(end 0.120396 0.2794)
			(stroke
				(width 0.1)
				(type default)
			)
			(layer "F.Fab")
		)
		(fp_line
			(start 0.12065 -0.3048)
			(end 0.67945 -0.3048)
			(stroke
				(width 0.1)
				(type default)
			)
			(layer "F.Fab")
		)
		(fp_line
			(start 0.12065 -0.2794)
			(end 0.12065 -0.3048)
			(stroke
				(width 0.1)
				(type default)
			)
			(layer "F.Fab")
		)
		(fp_line
			(start 0.67945 -0.3048)
			(end 0.67945 0.3048)
			(stroke
				(width 0.1)
				(type default)
			)
			(layer "F.Fab")
		)
		(fp_line
			(start 0.67945 0.3048)
			(end 0.120396 0.3048)
			(stroke
				(width 0.1)
				(type default)
			)
			(layer "F.Fab")
		)
		(pad "1" smd circle
			(at -0.40005 0)
			(size 0 0)
			(layers "F.Cu" "F.Mask" "F.Paste")
			(net "SMB_SCM_2_R5_SDA")
		)
		(pad "2" smd circle
			(at 0.40005 0)
			(size 0 0)
			(layers "F.Cu" "F.Mask" "F.Paste")
			(net "SMB_SCM_2_R6_SDA")
		)
	)
)
